(kicad_pcb
	(version 20211014)
	(generator pcbnew)
	(general
    (thickness 1.6)
  )
	(paper "A4")
	(title_block
    (title "SA800U (Snapdragon 845) Baseboard")
    (date "2023-10-19")
    (rev "1.0.3")
    (company "Antmicro Ltd.")
    (comment 1 "www.antmicro.com")
		(comment 9 "footprints 243-252 of 589")
	)
	(layers
    (0 "F.Cu" signal)
    (1 "In1.Cu" power)
    (2 "In2.Cu" signal)
    (3 "In3.Cu" signal)
    (4 "In4.Cu" power)
    (31 "B.Cu" signal)
    (32 "B.Adhes" user "B.Adhesive")
    (33 "F.Adhes" user "F.Adhesive")
    (34 "B.Paste" user)
    (35 "F.Paste" user)
    (36 "B.SilkS" user "B.Silkscreen")
    (37 "F.SilkS" user "F.Silkscreen")
    (38 "B.Mask" user)
    (39 "F.Mask" user)
    (40 "Dwgs.User" user "User.Drawings")
    (41 "Cmts.User" user "User.Comments")
    (42 "Eco1.User" user "User.Eco1")
    (43 "Eco2.User" user "User.Eco2")
    (44 "Edge.Cuts" user)
    (45 "Margin" user)
    (46 "B.CrtYd" user "B.Courtyard")
    (47 "F.CrtYd" user "F.Courtyard")
    (48 "B.Fab" user)
    (49 "F.Fab" user)
  )
	(footprint "sa800u-baseboard-hw-footprints:R_0603_1608Metric" (layer "F.Cu")
    (tedit 5D5D3E92)
    (at 117.6 92)
    (descr "Resistor SMD 0603")
    (tags "resistor SMD 0603")
    (property "Author" "Antmicro")
    (property "Current" "1A")
    (property "License" "Apache-2.0")
    (property "MPN" "CR0603-J/-000ELF")
    (property "Manufacturer" "Bourns")
    (property "Sheetfile" "camera-interface.kicad_sch")
    (property "Sheetname" "Camera Interface")
    (property "Tolerance" "")
    (property "Val" "0R")
    (attr smd)
    (fp_text reference "R84" (at -1.1 -0.51) (layer "F.SilkS")
      (effects (font (size 0.7 0.7) (thickness 0.15)) (justify left bottom))
    )
    (fp_text value "R_0R_0603" (at 0 1.6) (layer "F.Fab")
      (effects (font (size 0.7 0.7) (thickness 0.15)) (justify left bottom))
    )
    (fp_text user "License: Apache-2.0" (at -1.25 5.9) (layer "F.Fab") hide
      (effects (font (size 0.7 0.7) (thickness 0.15)) (justify left bottom))
    )
    (fp_text user "Author: Antmicro" (at -1.25 4.9) (layer "F.Fab") hide
      (effects (font (size 0.7 0.7) (thickness 0.15)) (justify left bottom))
    )
    (fp_text user "${REFERENCE}" (at -1.25 3.898) (layer "F.Fab") hide
      (effects (font (size 0.7 0.7) (thickness 0.15)) (justify left bottom))
    )
    (fp_line (start -0.3 -0.3) (end 0.3 -0.3) (layer "F.SilkS") (width 0.15))
    (fp_line (start -0.3 0.3) (end 0.3 0.3) (layer "F.SilkS") (width 0.15))
    (fp_rect (start -1.25 -0.7) (end 1.25 0.7) (layer "F.CrtYd") (width 0.05) (fill none))
    (fp_rect (start -0.8 -0.4) (end 0.8 0.4) (layer "F.Fab") (width 0.15) (fill none))
    (pad "1" smd roundrect (at -0.7 0) (size 0.6 0.8) (layers "F.Cu" "F.Paste" "F.Mask") (roundrect_rratio 0.2)
      (net 231 "/Camera Interface/3V3_CAM") (pintype "passive"))
    (pad "2" smd roundrect (at 0.7 0) (size 0.6 0.8) (layers "F.Cu" "F.Paste" "F.Mask") (roundrect_rratio 0.2)
      (net 131 "3V3_SYS") (pintype "passive"))
  )
	(footprint "sa800u-baseboard-hw-footprints:R_0402_1005Metric" (layer "F.Cu")
    (tedit 5FD9C158)
    (at 91 135)
    (descr "Resistor SMD 0402")
    (tags "resistor SMD 0402")
    (property "Author" "Antmicro")
    (property "License" "Apache-2.0")
    (property "MPN" "CR0402-FX-1002GLF")
    (property "Manufacturer" "Bourns")
    (property "Sheetfile" "usb-pd.kicad_sch")
    (property "Sheetname" "USB-PD")
    (property "Tolerance" "1%")
    (property "Val" "10k")
    (attr smd)
    (fp_text reference "R153" (at 0.84 0.31) (layer "F.SilkS")
      (effects (font (size 0.7 0.7) (thickness 0.15)) (justify left bottom))
    )
    (fp_text value "R_10k_0402" (at 0 1.4) (layer "F.Fab")
      (effects (font (size 0.7 0.7) (thickness 0.15)) (justify left bottom))
    )
    (fp_text user "License: Apache-2.0" (at -0.95 5.169) (layer "F.Fab") hide
      (effects (font (size 0.7 0.7) (thickness 0.15)) (justify left bottom))
    )
    (fp_text user "${REFERENCE}" (at -0.95 3.168) (layer "F.Fab") hide
      (effects (font (size 0.7 0.7) (thickness 0.15)) (justify left bottom))
    )
    (fp_text user "Author: Antmicro" (at -0.95 4.169) (layer "F.Fab") hide
      (effects (font (size 0.7 0.7) (thickness 0.15)) (justify left bottom))
    )
    (fp_rect (start -0.93 -0.47) (end 0.93 0.47) (layer "F.CrtYd") (width 0.05) (fill none))
    (fp_rect (start -0.5 -0.25) (end 0.5 0.25) (layer "F.Fab") (width 0.15) (fill none))
    (pad "1" smd roundrect (at -0.485 0) (size 0.59 0.64) (layers "F.Cu" "F.Paste" "F.Mask") (roundrect_rratio 0.25)
      (net 351 "USB_PD_DISABLE") (pintype "passive"))
    (pad "2" smd roundrect (at 0.485 0) (size 0.59 0.64) (layers "F.Cu" "F.Paste" "F.Mask") (roundrect_rratio 0.25)
      (net 1 "GND") (pintype "passive"))
  )
	(footprint "sa800u-baseboard-hw-footprints:R_0402_1005Metric" (layer "F.Cu")
    (tedit 5FD9C158)
    (at 147.95 136.9 -90)
    (descr "Resistor SMD 0402")
    (tags "resistor SMD 0402")
    (property "Author" "Antmicro")
    (property "License" "Apache-2.0")
    (property "MPN" "CR0402-FX-5100GLF")
    (property "Manufacturer" "Bourns")
    (property "Sheetfile" "hdmi-converter.kicad_sch")
    (property "Sheetname" "HDMI converter")
    (property "Tolerance" "1%")
    (property "Val" "510R")
    (attr smd)
    (fp_text reference "R56" (at -4.57 16.84 -90) (layer "F.SilkS")
      (effects (font (size 0.7 0.7) (thickness 0.15)) (justify left bottom))
    )
    (fp_text value "R_510R_0402" (at 0 1.4 -90) (layer "F.Fab")
      (effects (font (size 0.7 0.7) (thickness 0.15)) (justify left bottom))
    )
    (fp_text user "${REFERENCE}" (at -0.95 3.168 -90) (layer "F.Fab") hide
      (effects (font (size 0.7 0.7) (thickness 0.15)) (justify left bottom))
    )
    (fp_text user "Author: Antmicro" (at -0.95 4.169 -90) (layer "F.Fab") hide
      (effects (font (size 0.7 0.7) (thickness 0.15)) (justify left bottom))
    )
    (fp_text user "License: Apache-2.0" (at -0.95 5.169 -90) (layer "F.Fab") hide
      (effects (font (size 0.7 0.7) (thickness 0.15)) (justify left bottom))
    )
    (fp_rect (start -0.93 -0.47) (end 0.93 0.47) (layer "F.CrtYd") (width 0.05) (fill none))
    (fp_rect (start -0.5 -0.25) (end 0.5 0.25) (layer "F.Fab") (width 0.15) (fill none))
    (pad "1" smd roundrect (at -0.485 0 270) (size 0.59 0.64) (layers "F.Cu" "F.Paste" "F.Mask") (roundrect_rratio 0.25)
      (net 193 "/HDMI converter/HDMI_TX2_P") (pintype "passive"))
    (pad "2" smd roundrect (at 0.485 0 270) (size 0.59 0.64) (layers "F.Cu" "F.Paste" "F.Mask") (roundrect_rratio 0.25)
      (net 209 "/HDMI converter/VCOM") (pintype "passive"))
  )
	(footprint "sa800u-baseboard-hw-footprints:R_0402_1005Metric" (layer "F.Cu")
    (tedit 5FD9C158)
    (at 110.8 91.85 90)
    (descr "Resistor SMD 0402")
    (tags "resistor SMD 0402")
    (property "Author" "Antmicro")
    (property "License" "Apache-2.0")
    (property "MPN" "CR0402-FX-2001GLF")
    (property "Manufacturer" "Bourns")
    (property "Sheetfile" "camera-interface.kicad_sch")
    (property "Sheetname" "Camera Interface")
    (property "Tolerance" "1%")
    (property "Val" "2k")
    (attr smd)
    (fp_text reference "R87" (at -0.94 -1.65 90) (layer "F.SilkS")
      (effects (font (size 0.7 0.7) (thickness 0.15)) (justify left bottom))
    )
    (fp_text value "R_2k_0402" (at 0 1.4 90) (layer "F.Fab")
      (effects (font (size 0.7 0.7) (thickness 0.15)) (justify left bottom))
    )
    (fp_text user "License: Apache-2.0" (at -0.95 5.169 90) (layer "F.Fab") hide
      (effects (font (size 0.7 0.7) (thickness 0.15)) (justify left bottom))
    )
    (fp_text user "${REFERENCE}" (at -0.95 3.168 90) (layer "F.Fab") hide
      (effects (font (size 0.7 0.7) (thickness 0.15)) (justify left bottom))
    )
    (fp_text user "Author: Antmicro" (at -0.95 4.169 90) (layer "F.Fab") hide
      (effects (font (size 0.7 0.7) (thickness 0.15)) (justify left bottom))
    )
    (fp_rect (start -0.93 -0.47) (end 0.93 0.47) (layer "F.CrtYd") (width 0.05) (fill none))
    (fp_rect (start -0.5 -0.25) (end 0.5 0.25) (layer "F.Fab") (width 0.15) (fill none))
    (pad "1" smd roundrect (at -0.485 0 90) (size 0.59 0.64) (layers "F.Cu" "F.Paste" "F.Mask") (roundrect_rratio 0.25)
      (net 294 "/Camera Interface/CCI0_I2C_SCL_3V3") (pintype "passive"))
    (pad "2" smd roundrect (at 0.485 0 90) (size 0.59 0.64) (layers "F.Cu" "F.Paste" "F.Mask") (roundrect_rratio 0.25)
      (net 231 "/Camera Interface/3V3_CAM") (pintype "passive"))
  )
	(footprint "sa800u-baseboard-hw-footprints:R_0402_1005Metric" (layer "F.Cu")
    (tedit 5FD9C158)
    (at 93.75 121.7 -90)
    (descr "Resistor SMD 0402")
    (tags "resistor SMD 0402")
    (property "Author" "Antmicro")
    (property "Current" "1A")
    (property "License" "Apache-2.0")
    (property "MPN" "ERJ2GE0R00X")
    (property "Manufacturer" "Panasonic")
    (property "Sheetfile" "som.kicad_sch")
    (property "Sheetname" "SoM")
    (property "Tolerance" "")
    (property "Val" "0R")
    (attr smd)
    (fp_text reference "R176" (at 3.63 -0.37 -90) (layer "F.SilkS")
      (effects (font (size 0.7 0.7) (thickness 0.15)) (justify left bottom))
    )
    (fp_text value "R_0R_0402" (at 0 1.4 -90) (layer "F.Fab")
      (effects (font (size 0.7 0.7) (thickness 0.15)) (justify left bottom))
    )
    (fp_text user "${REFERENCE}" (at -0.95 3.168 -90) (layer "F.Fab") hide
      (effects (font (size 0.7 0.7) (thickness 0.15)) (justify left bottom))
    )
    (fp_text user "License: Apache-2.0" (at -0.95 5.169 -90) (layer "F.Fab") hide
      (effects (font (size 0.7 0.7) (thickness 0.15)) (justify left bottom))
    )
    (fp_text user "Author: Antmicro" (at -0.95 4.169 -90) (layer "F.Fab") hide
      (effects (font (size 0.7 0.7) (thickness 0.15)) (justify left bottom))
    )
    (fp_rect (start -0.93 -0.47) (end 0.93 0.47) (layer "F.CrtYd") (width 0.05) (fill none))
    (fp_rect (start -0.5 -0.25) (end 0.5 0.25) (layer "F.Fab") (width 0.15) (fill none))
    (pad "1" smd roundrect (at -0.485 0 270) (size 0.59 0.64) (layers "F.Cu" "F.Paste" "F.Mask") (roundrect_rratio 0.25)
      (net 420 "Net-(R176-Pad1)") (pintype "passive"))
    (pad "2" smd roundrect (at 0.485 0 270) (size 0.59 0.64) (layers "F.Cu" "F.Paste" "F.Mask") (roundrect_rratio 0.25)
      (net 424 "/SoM/VBAT_SOM") (pintype "passive"))
  )
	(footprint "sa800u-baseboard-hw-footprints:R_0402_1005Metric" (layer "F.Cu")
    (tedit 5FD9C158)
    (at 92.75 121.7 -90)
    (descr "Resistor SMD 0402")
    (tags "resistor SMD 0402")
    (property "Author" "Antmicro")
    (property "Current" "1A")
    (property "License" "Apache-2.0")
    (property "MPN" "ERJ2GE0R00X")
    (property "Manufacturer" "Panasonic")
    (property "Sheetfile" "som.kicad_sch")
    (property "Sheetname" "SoM")
    (property "Tolerance" "")
    (property "Val" "0R")
    (attr smd)
    (fp_text reference "R177" (at 3.63 -0.37 -90) (layer "F.SilkS")
      (effects (font (size 0.7 0.7) (thickness 0.15)) (justify left bottom))
    )
    (fp_text value "R_0R_0402" (at 0 1.4 -90) (layer "F.Fab")
      (effects (font (size 0.7 0.7) (thickness 0.15)) (justify left bottom))
    )
    (fp_text user "${REFERENCE}" (at -0.95 3.168 -90) (layer "F.Fab") hide
      (effects (font (size 0.7 0.7) (thickness 0.15)) (justify left bottom))
    )
    (fp_text user "License: Apache-2.0" (at -0.95 5.169 -90) (layer "F.Fab") hide
      (effects (font (size 0.7 0.7) (thickness 0.15)) (justify left bottom))
    )
    (fp_text user "Author: Antmicro" (at -0.95 4.169 -90) (layer "F.Fab") hide
      (effects (font (size 0.7 0.7) (thickness 0.15)) (justify left bottom))
    )
    (fp_rect (start -0.93 -0.47) (end 0.93 0.47) (layer "F.CrtYd") (width 0.05) (fill none))
    (fp_rect (start -0.5 -0.25) (end 0.5 0.25) (layer "F.Fab") (width 0.15) (fill none))
    (pad "1" smd roundrect (at -0.485 0 270) (size 0.59 0.64) (layers "F.Cu" "F.Paste" "F.Mask") (roundrect_rratio 0.25)
      (net 421 "Net-(R177-Pad1)") (pintype "passive"))
    (pad "2" smd roundrect (at 0.485 0 270) (size 0.59 0.64) (layers "F.Cu" "F.Paste" "F.Mask") (roundrect_rratio 0.25)
      (net 424 "/SoM/VBAT_SOM") (pintype "passive"))
  )
	(footprint "sa800u-baseboard-hw-footprints:R_0402_1005Metric" (layer "F.Cu")
    (tedit 5FD9C158)
    (at 91.75 121.7 -90)
    (descr "Resistor SMD 0402")
    (tags "resistor SMD 0402")
    (property "Author" "Antmicro")
    (property "Current" "1A")
    (property "License" "Apache-2.0")
    (property "MPN" "ERJ2GE0R00X")
    (property "Manufacturer" "Panasonic")
    (property "Sheetfile" "som.kicad_sch")
    (property "Sheetname" "SoM")
    (property "Tolerance" "")
    (property "Val" "0R")
    (attr smd)
    (fp_text reference "R178" (at 3.63 -0.37 -90) (layer "F.SilkS")
      (effects (font (size 0.7 0.7) (thickness 0.15)) (justify left bottom))
    )
    (fp_text value "R_0R_0402" (at 0 1.4 -90) (layer "F.Fab")
      (effects (font (size 0.7 0.7) (thickness 0.15)) (justify left bottom))
    )
    (fp_text user "License: Apache-2.0" (at -0.95 5.169 -90) (layer "F.Fab") hide
      (effects (font (size 0.7 0.7) (thickness 0.15)) (justify left bottom))
    )
    (fp_text user "Author: Antmicro" (at -0.95 4.169 -90) (layer "F.Fab") hide
      (effects (font (size 0.7 0.7) (thickness 0.15)) (justify left bottom))
    )
    (fp_text user "${REFERENCE}" (at -0.95 3.168 -90) (layer "F.Fab") hide
      (effects (font (size 0.7 0.7) (thickness 0.15)) (justify left bottom))
    )
    (fp_rect (start -0.93 -0.47) (end 0.93 0.47) (layer "F.CrtYd") (width 0.05) (fill none))
    (fp_rect (start -0.5 -0.25) (end 0.5 0.25) (layer "F.Fab") (width 0.15) (fill none))
    (pad "1" smd roundrect (at -0.485 0 270) (size 0.59 0.64) (layers "F.Cu" "F.Paste" "F.Mask") (roundrect_rratio 0.25)
      (net 422 "Net-(R178-Pad1)") (pintype "passive"))
    (pad "2" smd roundrect (at 0.485 0 270) (size 0.59 0.64) (layers "F.Cu" "F.Paste" "F.Mask") (roundrect_rratio 0.25)
      (net 424 "/SoM/VBAT_SOM") (pintype "passive"))
  )
	(footprint "sa800u-baseboard-hw-footprints:R_0402_1005Metric" (layer "F.Cu")
    (tedit 5FD9C158)
    (at 90.75 121.7 -90)
    (descr "Resistor SMD 0402")
    (tags "resistor SMD 0402")
    (property "Author" "Antmicro")
    (property "Current" "1A")
    (property "License" "Apache-2.0")
    (property "MPN" "ERJ2GE0R00X")
    (property "Manufacturer" "Panasonic")
    (property "Sheetfile" "som.kicad_sch")
    (property "Sheetname" "SoM")
    (property "Tolerance" "")
    (property "Val" "0R")
    (attr smd)
    (fp_text reference "R179" (at 3.63 -0.37 -90) (layer "F.SilkS")
      (effects (font (size 0.7 0.7) (thickness 0.15)) (justify left bottom))
    )
    (fp_text value "R_0R_0402" (at 0 1.4 -90) (layer "F.Fab")
      (effects (font (size 0.7 0.7) (thickness 0.15)) (justify left bottom))
    )
    (fp_text user "${REFERENCE}" (at -0.95 3.168 -90) (layer "F.Fab") hide
      (effects (font (size 0.7 0.7) (thickness 0.15)) (justify left bottom))
    )
    (fp_text user "Author: Antmicro" (at -0.95 4.169 -90) (layer "F.Fab") hide
      (effects (font (size 0.7 0.7) (thickness 0.15)) (justify left bottom))
    )
    (fp_text user "License: Apache-2.0" (at -0.95 5.169 -90) (layer "F.Fab") hide
      (effects (font (size 0.7 0.7) (thickness 0.15)) (justify left bottom))
    )
    (fp_rect (start -0.93 -0.47) (end 0.93 0.47) (layer "F.CrtYd") (width 0.05) (fill none))
    (fp_rect (start -0.5 -0.25) (end 0.5 0.25) (layer "F.Fab") (width 0.15) (fill none))
    (pad "1" smd roundrect (at -0.485 0 270) (size 0.59 0.64) (layers "F.Cu" "F.Paste" "F.Mask") (roundrect_rratio 0.25)
      (net 423 "Net-(R179-Pad1)") (pintype "passive"))
    (pad "2" smd roundrect (at 0.485 0 270) (size 0.59 0.64) (layers "F.Cu" "F.Paste" "F.Mask") (roundrect_rratio 0.25)
      (net 1 "GND") (pintype "passive"))
  )
	(footprint "sa800u-baseboard-hw-footprints:R_0402_1005Metric" (layer "F.Cu")
    (tedit 5FD9C158)
    (at 81.45 139.3)
    (descr "Resistor SMD 0402")
    (tags "resistor SMD 0402")
    (property "Author" "Antmicro")
    (property "License" "Apache-2.0")
    (property "MPN" "CR0402-FX-4700GLF")
    (property "Manufacturer" "Bourns")
    (property "Sheetfile" "usb-pd.kicad_sch")
    (property "Sheetname" "USB-PD")
    (property "Tolerance" "1%")
    (property "Val" "470R")
    (attr smd)
    (fp_text reference "R158" (at 0.58 -0.91) (layer "F.SilkS")
      (effects (font (size 0.7 0.7) (thickness 0.15)) (justify left bottom))
    )
    (fp_text value "R_470R_0402" (at 0 1.4) (layer "F.Fab")
      (effects (font (size 0.7 0.7) (thickness 0.15)) (justify left bottom))
    )
    (fp_text user "License: Apache-2.0" (at -0.95 5.169) (layer "F.Fab") hide
      (effects (font (size 0.7 0.7) (thickness 0.15)) (justify left bottom))
    )
    (fp_text user "${REFERENCE}" (at -0.95 3.168) (layer "F.Fab") hide
      (effects (font (size 0.7 0.7) (thickness 0.15)) (justify left bottom))
    )
    (fp_text user "Author: Antmicro" (at -0.95 4.169) (layer "F.Fab") hide
      (effects (font (size 0.7 0.7) (thickness 0.15)) (justify left bottom))
    )
    (fp_rect (start -0.93 -0.47) (end 0.93 0.47) (layer "F.CrtYd") (width 0.05) (fill none))
    (fp_rect (start -0.5 -0.25) (end 0.5 0.25) (layer "F.Fab") (width 0.15) (fill none))
    (pad "1" smd roundrect (at -0.485 0) (size 0.59 0.64) (layers "F.Cu" "F.Paste" "F.Mask") (roundrect_rratio 0.25)
      (net 107 "/USB-PD/PD_VBUS") (pintype "passive"))
    (pad "2" smd roundrect (at 0.485 0) (size 0.59 0.64) (layers "F.Cu" "F.Paste" "F.Mask") (roundrect_rratio 0.25)
      (net 364 "Net-(C153-Pad1)") (pintype "passive"))
  )
	(footprint "sa800u-baseboard-hw-footprints:C_0805_2012Metric" (layer "F.Cu")
    (tedit 5FD9C126)
    (at 91.83 92.68 -90)
    (descr "Capacitor SMD 0805")
    (tags "capacitor SMD 0805")
    (property "Author" "Antmicro")
    (property "Dielectric" "")
    (property "License" "Apache-2.0")
    (property "MPN" "GRM21BR60J107ME15L")
    (property "Manufacturer" "Murata")
    (property "Sheetfile" "som.kicad_sch")
    (property "Sheetname" "SoM")
    (property "Val" "100u")
    (property "Voltage" "")
    (attr smd)
    (fp_text reference "C100" (at 4.46 -0.38 -90) (layer "F.SilkS")
      (effects (font (size 0.7 0.7) (thickness 0.15)) (justify left bottom))
    )
    (fp_text value "C_100u_0805" (at 0 1.947 -90) (layer "F.Fab")
      (effects (font (size 0.7 0.7) (thickness 0.15)) (justify left bottom))
    )
    (fp_text user "Author: Antmicro" (at -1.9 5.947 -90) (layer "F.Fab") hide
      (effects (font (size 0.7 0.7) (thickness 0.15)) (justify left bottom))
    )
    (fp_text user "License: Apache-2.0" (at -1.9 4.947 -90) (layer "F.Fab") hide
      (effects (font (size 0.7 0.7) (thickness 0.15)) (justify left bottom))
    )
    (fp_text user "${REFERENCE}" (at -1.9 3.947 -90) (layer "F.Fab") hide
      (effects (font (size 0.7 0.7) (thickness 0.15)) (justify left bottom))
    )
    (fp_line (start -0.3 0.8) (end 0.3 0.8) (layer "F.SilkS") (width 0.15))
    (fp_line (start -0.3 -0.8) (end 0.3 -0.8) (layer "F.SilkS") (width 0.15))
    (fp_rect (start -1.9 -0.93) (end 1.9 0.93) (layer "F.CrtYd") (width 0.05) (fill none))
    (fp_rect (start -0.95 -0.675) (end 0.95 0.675) (layer "F.Fab") (width 0.15) (fill none))
    (pad "1" smd rect (at -1.05 0 270) (size 1.2 1.2) (layers "F.Cu" "F.Paste" "F.Mask")
      (net 424 "/SoM/VBAT_SOM") (pintype "passive"))
    (pad "2" smd rect (at 1.05 0 270) (size 1.2 1.2) (layers "F.Cu" "F.Paste" "F.Mask")
      (net 1 "GND") (pintype "passive"))
  )
)
